# S9S_MB_2U (Grand Teton) — schematic netlist excerpt (pin names and nets, part order shuffled) for the footprints in the layout excerpt that follows; sources: Cadence DE-HDL packaged netlist, KiCad conversion of 03242023_DA0F0TMBIJ0_F0T_Motherboard_J_brd_V01_OCP.brd

C726  Q_CAP_DIFFBUS  DIFF BUS_0.22UF 6.3V 20% X6S  pkg C0201  page 176 : \1\ = P5E_CPU1_PE0_TX_C_DN<7> ; \2\ = P5E_CPU1_PE0_TX_DN<7>
PC399_P1_1  Q_CAP  1UF 16V 10% X6S  pkg C0402  page 289 : A = SW_P12V_PVCCFA_EHV_FIVRA_CPU1_R ; B = GND
R1472  Q_RES  33.2 1% CHIP  pkg 0402LF  page 131 : A = JTAG_DBP_PRESENT_R_N ; B = FM_BMC_DBP_PRESENT_R_N

(kicad_pcb
	(version 20260206)
	(generator "pcbnew")
	(generator_version "10.0")
	(general
		(thickness 1.6)
		(legacy_teardrops no)
	)
	(paper "A4")
	(title_block
		(title "03242023_DA0F0TMBIJ0_F0T_Motherboard_J_brd_V01_OCP.brd")
		(comment 1 "Grand Teton / footprints 3680-3682 of 6105")
	)
	(layers
		(0 "F.Cu" signal "TOP")
		(4 "In1.Cu" signal "GND")
		(6 "In2.Cu" signal "IN1")
		(8 "In3.Cu" signal "GND1")
		(10 "In4.Cu" signal "IN2")
		(12 "In5.Cu" signal "GND2")
		(14 "In6.Cu" signal "IN3")
		(16 "In7.Cu" signal "GND3")
		(18 "In8.Cu" signal "VCC")
		(20 "In9.Cu" signal "VCC1")
		(22 "In10.Cu" signal "GND4")
		(24 "In11.Cu" signal "IN4")
		(26 "In12.Cu" signal "GND5")
		(28 "In13.Cu" signal "IN5")
		(30 "In14.Cu" signal "GND6")
		(32 "In15.Cu" signal "IN6")
		(34 "In16.Cu" signal "GND7")
		(2 "B.Cu" signal "BOTTOM")
		(9 "F.Adhes" user "F.Adhesive")
		(11 "B.Adhes" user "B.Adhesive")
		(13 "F.Paste" user "Package Geometry/Pastemask Top")
		(15 "B.Paste" user "Package Geometry/Pastemask Bottom")
		(5 "F.SilkS" user "Ref Des/Silkscreen Top")
		(7 "B.SilkS" user "Ref Des/Silkscreen Bottom")
		(1 "F.Mask" user "Board Geometry/Soldermask Top")
		(3 "B.Mask" user "Board Geometry/Soldermask Bottom")
		(17 "Dwgs.User" user "User.Drawings")
		(19 "Cmts.User" user "User.Comments")
		(21 "Eco1.User" user "User.Eco1")
		(23 "Eco2.User" user "User.Eco2")
		(25 "Edge.Cuts" user "Board Geometry/Outline")
		(27 "Margin" user)
		(31 "F.CrtYd" user "Package Geometry/Place Bound Top")
		(29 "B.CrtYd" user "Package Geometry/Place Bound Bottom")
		(35 "F.Fab" user "Ref Des/Assembly Top")
		(33 "B.Fab" user "Ref Des/Assembly Bottom")
	)
	(footprint ""
		(layer "F.Cu")
		(at 175.595534 -353.62261 -90)
		(property "Reference" "PC399_P1_1"
			(at 0 0 270)
			(layer "F.SilkS")
			(hide yes)
			(effects
				(font
					(size 1.27 1.27)
				)
			)
		)
		(property "Value" ""
			(at 0 0 270)
			(layer "F.Fab")
			(effects
				(font
					(size 1.27 1.27)
				)
			)
		)
		(duplicate_pad_numbers_are_jumpers no)
		(fp_line
			(start -0.7874 0.4064)
			(end -0.7874 -0.4064)
			(stroke
				(width 0.1524)
				(type default)
			)
			(layer "F.SilkS")
		)
		(fp_line
			(start 0.7874 0.4064)
			(end -0.7874 0.4064)
			(stroke
				(width 0.1524)
				(type default)
			)
			(layer "F.SilkS")
		)
		(fp_line
			(start -0.7874 -0.4064)
			(end 0.7874 -0.4064)
			(stroke
				(width 0.1524)
				(type default)
			)
			(layer "F.SilkS")
		)
		(fp_line
			(start 0.7874 -0.4064)
			(end 0.7874 0.4064)
			(stroke
				(width 0.1524)
				(type default)
			)
			(layer "F.SilkS")
		)
		(fp_line
			(start -0.67945 0.3048)
			(end -0.67945 -0.305054)
			(stroke
				(width 0.1)
				(type default)
			)
			(layer "F.Fab")
		)
		(fp_line
			(start -0.12065 0.3048)
			(end -0.67945 0.3048)
			(stroke
				(width 0.1)
				(type default)
			)
			(layer "F.Fab")
		)
		(fp_line
			(start 0.120396 0.3048)
			(end 0.120396 0.2794)
			(stroke
				(width 0.1)
				(type default)
			)
			(layer "F.Fab")
		)
		(fp_line
			(start 0.67945 0.3048)
			(end 0.120396 0.3048)
			(stroke
				(width 0.1)
				(type default)
			)
			(layer "F.Fab")
		)
		(fp_line
			(start -0.12065 0.2794)
			(end -0.12065 0.3048)
			(stroke
				(width 0.1)
				(type default)
			)
			(layer "F.Fab")
		)
		(fp_line
			(start 0.120396 0.2794)
			(end -0.12065 0.2794)
			(stroke
				(width 0.1)
				(type default)
			)
			(layer "F.Fab")
		)
		(fp_line
			(start -0.12065 -0.2794)
			(end 0.12065 -0.2794)
			(stroke
				(width 0.1)
				(type default)
			)
			(layer "F.Fab")
		)
		(fp_line
			(start 0.12065 -0.2794)
			(end 0.12065 -0.3048)
			(stroke
				(width 0.1)
				(type default)
			)
			(layer "F.Fab")
		)
		(fp_line
			(start 0.12065 -0.3048)
			(end 0.67945 -0.3048)
			(stroke
				(width 0.1)
				(type default)
			)
			(layer "F.Fab")
		)
		(fp_line
			(start 0.67945 -0.3048)
			(end 0.67945 0.3048)
			(stroke
				(width 0.1)
				(type default)
			)
			(layer "F.Fab")
		)
		(fp_line
			(start -0.67945 -0.305054)
			(end -0.12065 -0.305054)
			(stroke
				(width 0.1)
				(type default)
			)
			(layer "F.Fab")
		)
		(fp_line
			(start -0.12065 -0.305054)
			(end -0.12065 -0.2794)
			(stroke
				(width 0.1)
				(type default)
			)
			(layer "F.Fab")
		)
		(pad "1" smd circle
			(at -0.40005 0 270)
			(size 0 0)
			(layers "F.Cu" "F.Mask" "F.Paste")
			(net "SW_P12V_PVCCFA_EHV_FIVRA_CPU1_R")
		)
		(pad "2" smd circle
			(at 0.40005 0 270)
			(size 0 0)
			(layers "F.Cu" "F.Mask" "F.Paste")
			(net "GND")
		)
	)
	(footprint ""
		(layer "F.Cu")
		(at 385.716272 -58.703464 180)
		(property "Reference" "R1472"
			(at 0 0 180)
			(layer "F.SilkS")
			(hide yes)
			(effects
				(font
					(size 1.27 1.27)
				)
			)
		)
		(property "Value" ""
			(at 0 0 180)
			(layer "F.Fab")
			(effects
				(font
					(size 1.27 1.27)
				)
			)
		)
		(duplicate_pad_numbers_are_jumpers no)
		(fp_line
			(start 0.7874 0.4064)
			(end -0.7874 0.4064)
			(stroke
				(width 0.1524)
				(type default)
			)
			(layer "F.SilkS")
		)
		(fp_line
			(start 0.7874 -0.4064)
			(end 0.7874 0.4064)
			(stroke
				(width 0.1524)
				(type default)
			)
			(layer "F.SilkS")
		)
		(fp_line
			(start -0.7874 0.4064)
			(end -0.7874 -0.4064)
			(stroke
				(width 0.1524)
				(type default)
			)
			(layer "F.SilkS")
		)
		(fp_line
			(start -0.7874 -0.4064)
			(end 0.7874 -0.4064)
			(stroke
				(width 0.1524)
				(type default)
			)
			(layer "F.SilkS")
		)
		(fp_line
			(start 0.67945 0.3048)
			(end 0.120396 0.3048)
			(stroke
				(width 0.1)
				(type default)
			)
			(layer "F.Fab")
		)
		(fp_line
			(start 0.67945 -0.3048)
			(end 0.67945 0.3048)
			(stroke
				(width 0.1)
				(type default)
			)
			(layer "F.Fab")
		)
		(fp_line
			(start 0.12065 -0.2794)
			(end 0.12065 -0.3048)
			(stroke
				(width 0.1)
				(type default)
			)
			(layer "F.Fab")
		)
		(fp_line
			(start 0.12065 -0.3048)
			(end 0.67945 -0.3048)
			(stroke
				(width 0.1)
				(type default)
			)
			(layer "F.Fab")
		)
		(fp_line
			(start 0.120396 0.3048)
			(end 0.120396 0.2794)
			(stroke
				(width 0.1)
				(type default)
			)
			(layer "F.Fab")
		)
		(fp_line
			(start 0.120396 0.2794)
			(end -0.12065 0.2794)
			(stroke
				(width 0.1)
				(type default)
			)
			(layer "F.Fab")
		)
		(fp_line
			(start -0.12065 0.3048)
			(end -0.67945 0.3048)
			(stroke
				(width 0.1)
				(type default)
			)
			(layer "F.Fab")
		)
		(fp_line
			(start -0.12065 0.2794)
			(end -0.12065 0.3048)
			(stroke
				(width 0.1)
				(type default)
			)
			(layer "F.Fab")
		)
		(fp_line
			(start -0.12065 -0.2794)
			(end 0.12065 -0.2794)
			(stroke
				(width 0.1)
				(type default)
			)
			(layer "F.Fab")
		)
		(fp_line
			(start -0.12065 -0.305054)
			(end -0.12065 -0.2794)
			(stroke
				(width 0.1)
				(type default)
			)
			(layer "F.Fab")
		)
		(fp_line
			(start -0.67945 0.3048)
			(end -0.67945 -0.305054)
			(stroke
				(width 0.1)
				(type default)
			)
			(layer "F.Fab")
		)
		(fp_line
			(start -0.67945 -0.305054)
			(end -0.12065 -0.305054)
			(stroke
				(width 0.1)
				(type default)
			)
			(layer "F.Fab")
		)
		(pad "1" smd circle
			(at -0.40005 0 180)
			(size 0 0)
			(layers "F.Cu" "F.Mask" "F.Paste")
			(net "JTAG_DBP_PRESENT_R_N")
		)
		(pad "2" smd circle
			(at 0.40005 0 180)
			(size 0 0)
			(layers "F.Cu" "F.Mask" "F.Paste")
			(net "FM_BMC_DBP_PRESENT_R_N")
		)
	)
	(footprint ""
		(layer "F.Cu")
		(at 72.460358 -402.371052 -90)
		(property "Reference" "C726"
			(at 0 0 270)
			(layer "F.SilkS")
			(hide yes)
			(effects
				(font
					(size 1.27 1.27)
				)
			)
		)
		(property "Value" ""
			(at 0 0 270)
			(layer "F.Fab")
			(effects
				(font
					(size 1.27 1.27)
				)
			)
		)
		(duplicate_pad_numbers_are_jumpers no)
		(fp_line
			(start -0.299974 0.150114)
			(end -0.299974 -0.150114)
			(stroke
				(width 0.1)
				(type default)
			)
			(layer "F.Fab")
		)
		(fp_line
			(start 0.299974 0.150114)
			(end -0.299974 0.150114)
			(stroke
				(width 0.1)
				(type default)
			)
			(layer "F.Fab")
		)
		(fp_line
			(start -0.299974 -0.150114)
			(end 0.299974 -0.150114)
			(stroke
				(width 0.1)
				(type default)
			)
			(layer "F.Fab")
		)
		(fp_line
			(start 0.299974 -0.150114)
			(end 0.299974 0.150114)
			(stroke
				(width 0.1)
				(type default)
			)
			(layer "F.Fab")
		)
		(pad "1" smd rect
			(at -0.2667 0 270)
			(size 0.3048 0.381)
			(layers "F.Cu" "F.Mask" "F.Paste")
			(net "P5E_CPU1_PE0_TX_C_DN<7>")
		)
		(pad "2" smd rect
			(at 0.2667 0 270)
			(size 0.3048 0.381)
			(layers "F.Cu" "F.Mask" "F.Paste")
			(net "P5E_CPU1_PE0_TX_DN<7>")
		)
	)
)
